(kicad_pcb
	(version 20260206)
	(generator "pcbnew")
	(generator_version "10.0")
	(general
		(thickness 1.6)
		(legacy_teardrops no)
	)
	(paper "A4")
	(title_block
		(title "baseboard — 13948-1b.1110WZS1818.brd")
		(comment 1 "Honey Badger (Wiwynn) / footprint 852 of 2523 (SU2), pads 359-481 of 896")
	)
	(layers
		(0 "F.Cu" signal "TOP")
		(4 "In1.Cu" signal "L2GND")
		(6 "In2.Cu" signal "L3")
		(8 "In3.Cu" signal "L4VCC")
		(10 "In4.Cu" signal "L5VCC")
		(12 "In5.Cu" signal "L6")
		(14 "In6.Cu" signal "L7GND")
		(2 "B.Cu" signal "BOTTOM")
		(9 "F.Adhes" user "F.Adhesive")
		(11 "B.Adhes" user "B.Adhesive")
		(13 "F.Paste" user "Package Geometry/Pastemask Top")
		(15 "B.Paste" user "Package Geometry/Pastemask Bottom")
		(5 "F.SilkS" user "Ref Des/Silkscreen Top")
		(7 "B.SilkS" user "Ref Des/Silkscreen Bottom")
		(1 "F.Mask" user "Board Geometry/Soldermask Top")
		(3 "B.Mask" user "Board Geometry/Soldermask Bottom")
		(17 "Dwgs.User" user "User.Drawings")
		(19 "Cmts.User" user "User.Comments")
		(21 "Eco1.User" user "User.Eco1")
		(23 "Eco2.User" user "User.Eco2")
		(25 "Edge.Cuts" user "Board Geometry/Outline")
		(27 "Margin" user)
		(31 "F.CrtYd" user "Package Geometry/Place Bound Top")
		(29 "B.CrtYd" user "Package Geometry/Place Bound Bottom")
		(35 "F.Fab" user "Ref Des/Assembly Top")
		(33 "B.Fab" user "Ref Des/Assembly Bottom")
	)
	(footprint ""
		(layer "F.Cu")
		(at 102.350062 -44.99991)
		(property "Reference" "SU2"
			(at 0 0 0)
			(layer "F.SilkS")
			(hide yes)
			(effects
				(font
					(size 1.27 1.27)
				)
			)
		)
		(property "Value" "SAS3008C0-1-DB-500020657-1-GP"
			(at -20.374102 -5.0292 0)
			(unlocked yes)
			(layer "F.Fab")
			(hide yes)
			(effects
				(font
					(size 1.016 1.016)
					(thickness 0.1524)
				)
			)
		)
		(property "Device Type" "BGA896D25H78"
			(at -20.374102 -6.5532 0)
			(unlocked yes)
			(layer "F.Fab")
			(hide yes)
			(effects
				(font
					(size 1.016 1.016)
					(thickness 0.1524)
				)
			)
		)
		(duplicate_pad_numbers_are_jumpers no)
		(pad "C3" smd circle
			(at -9.99998 -9.99998)
			(size 0.4064 0.4064)
			(layers "F.Cu" "F.Mask" "F.Paste")
			(net "Net_1043")
		)
		(pad "C4" smd circle
			(at -9.19988 -9.99998)
			(size 0.3556 0.3556)
			(layers "F.Cu" "F.Mask" "F.Paste")
			(net "Net_1044")
		)
		(pad "C5" smd circle
			(at -8.400034 -9.99998)
			(size 0.3556 0.3556)
			(layers "F.Cu" "F.Mask" "F.Paste")
			(net "GND")
		)
		(pad "C6" smd circle
			(at -7.599934 -9.99998)
			(size 0.3556 0.3556)
			(layers "F.Cu" "F.Mask" "F.Paste")
			(net "ICE1_TRST#")
		)
		(pad "C7" smd circle
			(at -6.800088 -9.99998)
			(size 0.3556 0.3556)
			(layers "F.Cu" "F.Mask" "F.Paste")
			(net "ICE0_TMS")
		)
		(pad "C8" smd circle
			(at -5.999988 -9.99998)
			(size 0.3556 0.3556)
			(layers "F.Cu" "F.Mask" "F.Paste")
			(net "ICE0_TDO")
		)
		(pad "C9" smd circle
			(at -5.199888 -9.99998)
			(size 0.3556 0.3556)
			(layers "F.Cu" "F.Mask" "F.Paste")
			(net "Net_1045")
		)
		(pad "C10" smd circle
			(at -4.400042 -9.99998)
			(size 0.3556 0.3556)
			(layers "F.Cu" "F.Mask" "F.Paste")
			(net "Net_1046")
		)
		(pad "C11" smd circle
			(at -3.599942 -9.99998)
			(size 0.3556 0.3556)
			(layers "F.Cu" "F.Mask" "F.Paste")
			(net "GND")
		)
		(pad "C12" smd circle
			(at -2.800096 -9.99998)
			(size 0.3556 0.3556)
			(layers "F.Cu" "F.Mask" "F.Paste")
			(net "P1V8_C_PG")
		)
		(pad "C13" smd circle
			(at -1.999996 -9.99998)
			(size 0.3556 0.3556)
			(layers "F.Cu" "F.Mask" "F.Paste")
			(net "Net_1030")
		)
		(pad "C14" smd circle
			(at -1.199896 -9.99998)
			(size 0.3556 0.3556)
			(layers "F.Cu" "F.Mask" "F.Paste")
			(net "GND")
		)
		(pad "C15" smd circle
			(at -0.40005 -9.99998)
			(size 0.3556 0.3556)
			(layers "F.Cu" "F.Mask" "F.Paste")
			(net "GND")
		)
		(pad "C16" smd circle
			(at 0.40005 -9.99998)
			(size 0.3556 0.3556)
			(layers "F.Cu" "F.Mask" "F.Paste")
			(net "LSI_TN")
		)
		(pad "C17" smd circle
			(at 1.199896 -9.99998)
			(size 0.3556 0.3556)
			(layers "F.Cu" "F.Mask" "F.Paste")
			(net "JTAG_IOC_TCK")
		)
		(pad "C18" smd circle
			(at 1.999996 -9.99998)
			(size 0.3556 0.3556)
			(layers "F.Cu" "F.Mask" "F.Paste")
			(net "IOC_TDO")
		)
		(pad "C19" smd circle
			(at 2.800096 -9.99998)
			(size 0.3556 0.3556)
			(layers "F.Cu" "F.Mask" "F.Paste")
			(net "XM_DATA_15")
		)
		(pad "C20" smd circle
			(at 3.599942 -9.99998)
			(size 0.3556 0.3556)
			(layers "F.Cu" "F.Mask" "F.Paste")
			(net "XM_DATA_6")
		)
		(pad "C21" smd circle
			(at 4.400042 -9.99998)
			(size 0.3556 0.3556)
			(layers "F.Cu" "F.Mask" "F.Paste")
			(net "XM_DATA_8")
		)
		(pad "C22" smd circle
			(at 5.199888 -9.99998)
			(size 0.3556 0.3556)
			(layers "F.Cu" "F.Mask" "F.Paste")
			(net "XM_DATA_5")
		)
		(pad "C23" smd circle
			(at 5.999988 -9.99998)
			(size 0.3556 0.3556)
			(layers "F.Cu" "F.Mask" "F.Paste")
			(net "XM_CLE")
		)
		(pad "C24" smd circle
			(at 6.800088 -9.99998)
			(size 0.3556 0.3556)
			(layers "F.Cu" "F.Mask" "F.Paste")
			(net "XM_DATA_7")
		)
		(pad "C25" smd circle
			(at 7.599934 -9.99998)
			(size 0.3556 0.3556)
			(layers "F.Cu" "F.Mask" "F.Paste")
			(net "XM_DATA_10")
		)
		(pad "C26" smd circle
			(at 8.400034 -9.99998)
			(size 0.3556 0.3556)
			(layers "F.Cu" "F.Mask" "F.Paste")
			(net "XM_DATA_9")
		)
		(pad "C27" smd circle
			(at 9.19988 -9.99998)
			(size 0.3556 0.3556)
			(layers "F.Cu" "F.Mask" "F.Paste")
			(net "XM_ADDR_2")
		)
		(pad "C28" smd circle
			(at 9.99998 -9.99998)
			(size 0.4064 0.4064)
			(layers "F.Cu" "F.Mask" "F.Paste")
			(net "XM_ADDR_5")
		)
		(pad "C29" smd circle
			(at 10.80008 -9.99998)
			(size 0.4064 0.4064)
			(layers "F.Cu" "F.Mask" "F.Paste")
			(net "XM_ADDR_11")
		)
		(pad "C30" smd circle
			(at 11.599926 -9.99998)
			(size 0.4064 0.4064)
			(layers "F.Cu" "F.Mask" "F.Paste")
			(net "XM_ADDR_13")
		)
		(pad "D1" smd circle
			(at -11.599926 -9.19988)
			(size 0.3556 0.3556)
			(layers "F.Cu" "F.Mask" "F.Paste")
			(net "Net_1073")
		)
		(pad "D2" smd circle
			(at -10.80008 -9.19988)
			(size 0.3556 0.3556)
			(layers "F.Cu" "F.Mask" "F.Paste")
			(net "Net_1047")
		)
		(pad "D3" smd circle
			(at -9.99998 -9.19988)
			(size 0.3556 0.3556)
			(layers "F.Cu" "F.Mask" "F.Paste")
			(net "Net_1048")
		)
		(pad "D4" smd circle
			(at -9.19988 -9.19988)
			(size 0.3556 0.3556)
			(layers "F.Cu" "F.Mask" "F.Paste")
			(net "P1V8_C")
		)
		(pad "D5" smd circle
			(at -8.400034 -9.19988)
			(size 0.3556 0.3556)
			(layers "F.Cu" "F.Mask" "F.Paste")
			(net "GND")
		)
		(pad "D6" smd circle
			(at -7.599934 -9.19988)
			(size 0.3556 0.3556)
			(layers "F.Cu" "F.Mask" "F.Paste")
			(net "P1V8_C")
		)
		(pad "D7" smd circle
			(at -6.800088 -9.19988)
			(size 0.3556 0.3556)
			(layers "F.Cu" "F.Mask" "F.Paste")
			(net "GND")
		)
		(pad "D8" smd circle
			(at -5.999988 -9.19988)
			(size 0.3556 0.3556)
			(layers "F.Cu" "F.Mask" "F.Paste")
			(net "P1V8_C")
		)
		(pad "D9" smd circle
			(at -5.199888 -9.19988)
			(size 0.3556 0.3556)
			(layers "F.Cu" "F.Mask" "F.Paste")
			(net "GND")
		)
		(pad "D10" smd circle
			(at -4.400042 -9.19988)
			(size 0.3556 0.3556)
			(layers "F.Cu" "F.Mask" "F.Paste")
			(net "P1V8_C")
		)
		(pad "D11" smd circle
			(at -3.599942 -9.19988)
			(size 0.3556 0.3556)
			(layers "F.Cu" "F.Mask" "F.Paste")
			(net "GND")
		)
		(pad "D12" smd circle
			(at -2.800096 -9.19988)
			(size 0.3556 0.3556)
			(layers "F.Cu" "F.Mask" "F.Paste")
			(net "GND")
		)
		(pad "D13" smd circle
			(at -1.999996 -9.19988)
			(size 0.3556 0.3556)
			(layers "F.Cu" "F.Mask" "F.Paste")
			(net "GND")
		)
		(pad "D14" smd circle
			(at -1.199896 -9.19988)
			(size 0.3556 0.3556)
			(layers "F.Cu" "F.Mask" "F.Paste")
			(net "GND")
		)
		(pad "D15" smd circle
			(at -0.40005 -9.19988)
			(size 0.3556 0.3556)
			(layers "F.Cu" "F.Mask" "F.Paste")
			(net "GND")
		)
		(pad "D16" smd circle
			(at 0.40005 -9.19988)
			(size 0.3556 0.3556)
			(layers "F.Cu" "F.Mask" "F.Paste")
			(net "P1V8_C")
		)
		(pad "D17" smd circle
			(at 1.199896 -9.19988)
			(size 0.3556 0.3556)
			(layers "F.Cu" "F.Mask" "F.Paste")
			(net "GND")
		)
		(pad "D18" smd circle
			(at 1.999996 -9.19988)
			(size 0.3556 0.3556)
			(layers "F.Cu" "F.Mask" "F.Paste")
			(net "P1V8_C")
		)
		(pad "D19" smd circle
			(at 2.800096 -9.19988)
			(size 0.3556 0.3556)
			(layers "F.Cu" "F.Mask" "F.Paste")
			(net "GND")
		)
		(pad "D20" smd circle
			(at 3.599942 -9.19988)
			(size 0.3556 0.3556)
			(layers "F.Cu" "F.Mask" "F.Paste")
			(net "P1V8_C")
		)
		(pad "D21" smd circle
			(at 4.400042 -9.19988)
			(size 0.3556 0.3556)
			(layers "F.Cu" "F.Mask" "F.Paste")
			(net "GND")
		)
		(pad "D22" smd circle
			(at 5.199888 -9.19988)
			(size 0.3556 0.3556)
			(layers "F.Cu" "F.Mask" "F.Paste")
			(net "P1V8_C")
		)
		(pad "D23" smd circle
			(at 5.999988 -9.19988)
			(size 0.3556 0.3556)
			(layers "F.Cu" "F.Mask" "F.Paste")
			(net "GND")
		)
		(pad "D24" smd circle
			(at 6.800088 -9.19988)
			(size 0.3556 0.3556)
			(layers "F.Cu" "F.Mask" "F.Paste")
			(net "P1V8_C")
		)
		(pad "D25" smd circle
			(at 7.599934 -9.19988)
			(size 0.3556 0.3556)
			(layers "F.Cu" "F.Mask" "F.Paste")
			(net "GND")
		)
		(pad "D26" smd circle
			(at 8.400034 -9.19988)
			(size 0.3556 0.3556)
			(layers "F.Cu" "F.Mask" "F.Paste")
			(net "P1V8_C")
		)
		(pad "D27" smd circle
			(at 9.19988 -9.19988)
			(size 0.3556 0.3556)
			(layers "F.Cu" "F.Mask" "F.Paste")
			(net "GND")
		)
		(pad "D28" smd circle
			(at 9.99998 -9.19988)
			(size 0.3556 0.3556)
			(layers "F.Cu" "F.Mask" "F.Paste")
			(net "XM_ADDR_9")
		)
		(pad "D29" smd circle
			(at 10.80008 -9.19988)
			(size 0.3556 0.3556)
			(layers "F.Cu" "F.Mask" "F.Paste")
			(net "XM_ADDR_10")
		)
		(pad "D30" smd circle
			(at 11.599926 -9.19988)
			(size 0.3556 0.3556)
			(layers "F.Cu" "F.Mask" "F.Paste")
			(net "XM_ADDR_17")
		)
		(pad "E1" smd circle
			(at -11.599926 -8.400034)
			(size 0.3556 0.3556)
			(layers "F.Cu" "F.Mask" "F.Paste")
			(net "Net_1074")
		)
		(pad "E2" smd circle
			(at -10.80008 -8.400034)
			(size 0.3556 0.3556)
			(layers "F.Cu" "F.Mask" "F.Paste")
			(net "Net_1049")
		)
		(pad "E3" smd circle
			(at -9.99998 -8.400034)
			(size 0.3556 0.3556)
			(layers "F.Cu" "F.Mask" "F.Paste")
			(net "GND")
		)
		(pad "E4" smd circle
			(at -9.19988 -8.400034)
			(size 0.3556 0.3556)
			(layers "F.Cu" "F.Mask" "F.Paste")
			(net "GND")
		)
		(pad "E5" smd circle
			(at -8.400034 -8.400034)
			(size 0.3556 0.3556)
			(layers "F.Cu" "F.Mask" "F.Paste")
			(net "P1V8_C")
		)
		(pad "E6" smd circle
			(at -7.599934 -8.400034)
			(size 0.3556 0.3556)
			(layers "F.Cu" "F.Mask" "F.Paste")
			(net "GND")
		)
		(pad "E7" smd circle
			(at -6.800088 -8.400034)
			(size 0.3556 0.3556)
			(layers "F.Cu" "F.Mask" "F.Paste")
			(net "P1V8_C")
		)
		(pad "E8" smd circle
			(at -5.999988 -8.400034)
			(size 0.3556 0.3556)
			(layers "F.Cu" "F.Mask" "F.Paste")
			(net "GND")
		)
		(pad "E9" smd circle
			(at -5.199888 -8.400034)
			(size 0.3556 0.3556)
			(layers "F.Cu" "F.Mask" "F.Paste")
			(net "P1V8_C")
		)
		(pad "E10" smd circle
			(at -4.400042 -8.400034)
			(size 0.3556 0.3556)
			(layers "F.Cu" "F.Mask" "F.Paste")
			(net "GND")
		)
		(pad "E11" smd circle
			(at -3.599942 -8.400034)
			(size 0.3556 0.3556)
			(layers "F.Cu" "F.Mask" "F.Paste")
			(net "GND")
		)
		(pad "E12" smd circle
			(at -2.800096 -8.400034)
			(size 0.3556 0.3556)
			(layers "F.Cu" "F.Mask" "F.Paste")
			(net "GND")
		)
		(pad "E13" smd circle
			(at -1.999996 -8.400034)
			(size 0.3556 0.3556)
			(layers "F.Cu" "F.Mask" "F.Paste")
			(net "GND")
		)
		(pad "E14" smd circle
			(at -1.199896 -8.400034)
			(size 0.3556 0.3556)
			(layers "F.Cu" "F.Mask" "F.Paste")
			(net "GND")
		)
		(pad "E15" smd circle
			(at -0.40005 -8.400034)
			(size 0.3556 0.3556)
			(layers "F.Cu" "F.Mask" "F.Paste")
			(net "P1V8_C")
		)
		(pad "E16" smd circle
			(at 0.40005 -8.400034)
			(size 0.3556 0.3556)
			(layers "F.Cu" "F.Mask" "F.Paste")
			(net "GND")
		)
		(pad "E17" smd circle
			(at 1.199896 -8.400034)
			(size 0.3556 0.3556)
			(layers "F.Cu" "F.Mask" "F.Paste")
			(net "P1V8_C")
		)
		(pad "E18" smd circle
			(at 1.999996 -8.400034)
			(size 0.3556 0.3556)
			(layers "F.Cu" "F.Mask" "F.Paste")
			(net "GND")
		)
		(pad "E19" smd circle
			(at 2.800096 -8.400034)
			(size 0.3556 0.3556)
			(layers "F.Cu" "F.Mask" "F.Paste")
			(net "P1V8_C")
		)
		(pad "E20" smd circle
			(at 3.599942 -8.400034)
			(size 0.3556 0.3556)
			(layers "F.Cu" "F.Mask" "F.Paste")
			(net "GND")
		)
		(pad "E21" smd circle
			(at 4.400042 -8.400034)
			(size 0.3556 0.3556)
			(layers "F.Cu" "F.Mask" "F.Paste")
			(net "P1V8_C")
		)
		(pad "E22" smd circle
			(at 5.199888 -8.400034)
			(size 0.3556 0.3556)
			(layers "F.Cu" "F.Mask" "F.Paste")
			(net "GND")
		)
		(pad "E23" smd circle
			(at 5.999988 -8.400034)
			(size 0.3556 0.3556)
			(layers "F.Cu" "F.Mask" "F.Paste")
			(net "P1V8_C")
		)
		(pad "E24" smd circle
			(at 6.800088 -8.400034)
			(size 0.3556 0.3556)
			(layers "F.Cu" "F.Mask" "F.Paste")
			(net "GND")
		)
		(pad "E25" smd circle
			(at 7.599934 -8.400034)
			(size 0.3556 0.3556)
			(layers "F.Cu" "F.Mask" "F.Paste")
			(net "P1V8_C")
		)
		(pad "E26" smd circle
			(at 8.400034 -8.400034)
			(size 0.3556 0.3556)
			(layers "F.Cu" "F.Mask" "F.Paste")
			(net "GND")
		)
		(pad "E27" smd circle
			(at 9.19988 -8.400034)
			(size 0.3556 0.3556)
			(layers "F.Cu" "F.Mask" "F.Paste")
			(net "P1V8_C")
		)
		(pad "E28" smd circle
			(at 9.99998 -8.400034)
			(size 0.3556 0.3556)
			(layers "F.Cu" "F.Mask" "F.Paste")
			(net "XM_ADDR_12")
		)
		(pad "E29" smd circle
			(at 10.80008 -8.400034)
			(size 0.3556 0.3556)
			(layers "F.Cu" "F.Mask" "F.Paste")
			(net "XM_DATA_14")
		)
		(pad "E30" smd circle
			(at 11.599926 -8.400034)
			(size 0.3556 0.3556)
			(layers "F.Cu" "F.Mask" "F.Paste")
			(net "XM_ADDR_14")
		)
		(pad "F1" smd circle
			(at -11.599926 -7.599934)
			(size 0.3556 0.3556)
			(layers "F.Cu" "F.Mask" "F.Paste")
			(net "Net_1075")
		)
		(pad "F2" smd circle
			(at -10.80008 -7.599934)
			(size 0.3556 0.3556)
			(layers "F.Cu" "F.Mask" "F.Paste")
			(net "Net_1050")
		)
		(pad "F3" smd circle
			(at -9.99998 -7.599934)
			(size 0.3556 0.3556)
			(layers "F.Cu" "F.Mask" "F.Paste")
			(net "Net_1051")
		)
		(pad "F4" smd circle
			(at -9.19988 -7.599934)
			(size 0.3556 0.3556)
			(layers "F.Cu" "F.Mask" "F.Paste")
			(net "P1V8_C")
		)
		(pad "F5" smd circle
			(at -8.400034 -7.599934)
			(size 0.3556 0.3556)
			(layers "F.Cu" "F.Mask" "F.Paste")
			(net "GND")
		)
		(pad "F6" smd circle
			(at -7.599934 -7.599934)
			(size 0.3556 0.3556)
			(layers "F.Cu" "F.Mask" "F.Paste")
			(net "Net_1052")
		)
		(pad "F7" smd circle
			(at -6.800088 -7.599934)
			(size 0.3556 0.3556)
			(layers "F.Cu" "F.Mask" "F.Paste")
			(net "Net_1053")
		)
		(pad "F8" smd circle
			(at -5.999988 -7.599934)
			(size 0.3556 0.3556)
			(layers "F.Cu" "F.Mask" "F.Paste")
			(net "Net_1054")
		)
		(pad "F9" smd circle
			(at -5.199888 -7.599934)
			(size 0.3556 0.3556)
			(layers "F.Cu" "F.Mask" "F.Paste")
			(net "Net_1055")
		)
		(pad "F10" smd circle
			(at -4.400042 -7.599934)
			(size 0.3556 0.3556)
			(layers "F.Cu" "F.Mask" "F.Paste")
			(net "Net_1056")
		)
		(pad "F11" smd circle
			(at -3.599942 -7.599934)
			(size 0.3556 0.3556)
			(layers "F.Cu" "F.Mask" "F.Paste")
			(net "GND")
		)
		(pad "F12" smd circle
			(at -2.800096 -7.599934)
			(size 0.3556 0.3556)
			(layers "F.Cu" "F.Mask" "F.Paste")
			(net "GND")
		)
		(pad "F13" smd circle
			(at -1.999996 -7.599934)
			(size 0.3556 0.3556)
			(layers "F.Cu" "F.Mask" "F.Paste")
			(net "GND")
		)
		(pad "F14" smd circle
			(at -1.199896 -7.599934)
			(size 0.3556 0.3556)
			(layers "F.Cu" "F.Mask" "F.Paste")
			(net "GND")
		)
		(pad "F15" smd circle
			(at -0.40005 -7.599934)
			(size 0.3556 0.3556)
			(layers "F.Cu" "F.Mask" "F.Paste")
			(net "GND")
		)
		(pad "F16" smd circle
			(at 0.40005 -7.599934)
			(size 0.3556 0.3556)
			(layers "F.Cu" "F.Mask" "F.Paste")
			(net "GND")
		)
		(pad "F17" smd circle
			(at 1.199896 -7.599934)
			(size 0.3556 0.3556)
			(layers "F.Cu" "F.Mask" "F.Paste")
			(net "GND")
		)
		(pad "F18" smd circle
			(at 1.999996 -7.599934)
			(size 0.3556 0.3556)
			(layers "F.Cu" "F.Mask" "F.Paste")
			(net "GND")
		)
		(pad "F19" smd circle
			(at 2.800096 -7.599934)
			(size 0.3556 0.3556)
			(layers "F.Cu" "F.Mask" "F.Paste")
			(net "GND")
		)
		(pad "F20" smd circle
			(at 3.599942 -7.599934)
			(size 0.3556 0.3556)
			(layers "F.Cu" "F.Mask" "F.Paste")
			(net "GND")
		)
		(pad "F21" smd circle
			(at 4.400042 -7.599934)
			(size 0.3556 0.3556)
			(layers "F.Cu" "F.Mask" "F.Paste")
			(net "GND")
		)
		(pad "F22" smd circle
			(at 5.199888 -7.599934)
			(size 0.3556 0.3556)
			(layers "F.Cu" "F.Mask" "F.Paste")
			(net "GND")
		)
		(pad "F23" smd circle
			(at 5.999988 -7.599934)
			(size 0.3556 0.3556)
			(layers "F.Cu" "F.Mask" "F.Paste")
			(net "GND")
		)
		(pad "F24" smd circle
			(at 6.800088 -7.599934)
			(size 0.3556 0.3556)
			(layers "F.Cu" "F.Mask" "F.Paste")
			(net "GND")
		)
		(pad "F25" smd circle
			(at 7.599934 -7.599934)
			(size 0.3556 0.3556)
			(layers "F.Cu" "F.Mask" "F.Paste")
			(net "GND")
		)
		(pad "F26" smd circle
			(at 8.400034 -7.599934)
			(size 0.3556 0.3556)
			(layers "F.Cu" "F.Mask" "F.Paste")
			(net "P1V8_C")
		)
		(pad "F27" smd circle
			(at 9.19988 -7.599934)
			(size 0.3556 0.3556)
			(layers "F.Cu" "F.Mask" "F.Paste")
			(net "GND")
		)
		(pad "F28" smd circle
			(at 9.99998 -7.599934)
			(size 0.3556 0.3556)
			(layers "F.Cu" "F.Mask" "F.Paste")
			(net "XM_ADDR_19")
		)
		(pad "F29" smd circle
			(at 10.80008 -7.599934)
			(size 0.3556 0.3556)
			(layers "F.Cu" "F.Mask" "F.Paste")
			(net "XM_ADDR_16")
		)
		(pad "F30" smd circle
			(at 11.599926 -7.599934)
			(size 0.3556 0.3556)
			(layers "F.Cu" "F.Mask" "F.Paste")
			(net "XM_ADDR_20")
		)
		(pad "G1" smd circle
			(at -11.599926 -6.800088)
			(size 0.3556 0.3556)
			(layers "F.Cu" "F.Mask" "F.Paste")
			(net "Net_1076")
		)
		(pad "G2" smd circle
			(at -10.80008 -6.800088)
			(size 0.3556 0.3556)
			(layers "F.Cu" "F.Mask" "F.Paste")
			(net "Net_1057")
		)
		(pad "G3" smd circle
			(at -9.99998 -6.800088)
			(size 0.3556 0.3556)
			(layers "F.Cu" "F.Mask" "F.Paste")
			(net "Net_1058")
		)
		(pad "G4" smd circle
			(at -9.19988 -6.800088)
			(size 0.3556 0.3556)
			(layers "F.Cu" "F.Mask" "F.Paste")
			(net "GND")
		)
		(pad "G5" smd circle
			(at -8.400034 -6.800088)
			(size 0.3556 0.3556)
			(layers "F.Cu" "F.Mask" "F.Paste")
			(net "P1V8_C")
		)
	)
)
